# T6G (Grand Teton) — schematic netlist excerpt (pin names and nets, part order shuffled) for the footprints in the layout excerpt that follows; sources: Cadence DE-HDL packaged netlist, KiCad conversion of 04192023_DAF0TMB3IC0_F0TG_MB_C_brd_V02_OCP.brd

PC281_1  Q_CAP  22UF 4V 20% X6S  pkg C0805  page 211 : A = PVDDCR_CPU0_P1 ; B = GND
C502  Q_CAP  100UF 4V 20% X6S  pkg C0805  page 279 : A = P1V8_CPU0_RT_1D ; B = GND
C2568  Q_CAP  22UF 4V 20% X6S  pkg C0402  page 70 : A = PVDDCR_SOC_P0 ; B = GND

(kicad_pcb
	(version 20260206)
	(generator "pcbnew")
	(generator_version "10.0")
	(general
		(thickness 1.6)
		(legacy_teardrops no)
	)
	(paper "A4")
	(title_block
		(title "04192023_DAF0TMB3IC0_F0TG_MB_C_brd_V02_OCP.brd")
		(comment 1 "Grand Teton / footprints 6092-6094 of 8354")
	)
	(layers
		(0 "F.Cu" signal "TOP")
		(4 "In1.Cu" signal "GND")
		(6 "In2.Cu" signal "IN1")
		(8 "In3.Cu" signal "GND1")
		(10 "In4.Cu" signal "IN2")
		(12 "In5.Cu" signal "GND2")
		(14 "In6.Cu" signal "IN3")
		(16 "In7.Cu" signal "GND3")
		(18 "In8.Cu" signal "VCC")
		(20 "In9.Cu" signal "VCC1")
		(22 "In10.Cu" signal "GND4")
		(24 "In11.Cu" signal "IN4")
		(26 "In12.Cu" signal "GND5")
		(28 "In13.Cu" signal "IN5")
		(30 "In14.Cu" signal "GND6")
		(32 "In15.Cu" signal "IN6")
		(34 "In16.Cu" signal "GND7")
		(2 "B.Cu" signal "BOTTOM")
		(9 "F.Adhes" user "F.Adhesive")
		(11 "B.Adhes" user "B.Adhesive")
		(13 "F.Paste" user "Package Geometry/Pastemask Top")
		(15 "B.Paste" user "Package Geometry/Pastemask Bottom")
		(5 "F.SilkS" user "Ref Des/Silkscreen Top")
		(7 "B.SilkS" user "Ref Des/Silkscreen Bottom")
		(1 "F.Mask" user "Board Geometry/Soldermask Top")
		(3 "B.Mask" user "Board Geometry/Soldermask Bottom")
		(17 "Dwgs.User" user "User.Drawings")
		(19 "Cmts.User" user "User.Comments")
		(21 "Eco1.User" user "User.Eco1")
		(23 "Eco2.User" user "User.Eco2")
		(25 "Edge.Cuts" user "Board Geometry/Outline")
		(27 "Margin" user)
		(31 "F.CrtYd" user "Package Geometry/Place Bound Top")
		(29 "B.CrtYd" user "Package Geometry/Place Bound Bottom")
		(35 "F.Fab" user "Ref Des/Assembly Top")
		(33 "B.Fab" user "Ref Des/Assembly Bottom")
	)
	(footprint ""
		(layer "B.Cu")
		(at 326.64527 -395.466062 -90)
		(property "Reference" "C502"
			(at 0 0 90)
			(layer "B.SilkS")
			(hide yes)
			(effects
				(font
					(size 1.27 1.27)
				)
				(justify mirror)
			)
		)
		(property "Value" ""
			(at 0 0 90)
			(layer "B.Fab")
			(effects
				(font
					(size 1.27 1.27)
				)
				(justify mirror)
			)
		)
		(duplicate_pad_numbers_are_jumpers no)
		(fp_line
			(start -1.524 0.762)
			(end 1.524 0.762)
			(stroke
				(width 0.1524)
				(type default)
			)
			(layer "B.SilkS")
		)
		(fp_line
			(start 1.524 0.762)
			(end 1.524 -0.762)
			(stroke
				(width 0.1524)
				(type default)
			)
			(layer "B.SilkS")
		)
		(fp_line
			(start -1.524 -0.762)
			(end -1.524 0.762)
			(stroke
				(width 0.1524)
				(type default)
			)
			(layer "B.SilkS")
		)
		(fp_line
			(start 1.524 -0.762)
			(end -1.524 -0.762)
			(stroke
				(width 0.1524)
				(type default)
			)
			(layer "B.SilkS")
		)
		(fp_line
			(start -1.1049 0.724916)
			(end -1.1049 -0.724916)
			(stroke
				(width 0.1)
				(type default)
			)
			(layer "B.Fab")
		)
		(fp_line
			(start 1.1049 0.724916)
			(end -1.1049 0.724916)
			(stroke
				(width 0.1)
				(type default)
			)
			(layer "B.Fab")
		)
		(fp_line
			(start -1.1049 -0.724916)
			(end 1.1049 -0.724916)
			(stroke
				(width 0.1)
				(type default)
			)
			(layer "B.Fab")
		)
		(fp_line
			(start 1.1049 -0.724916)
			(end 1.1049 0.724916)
			(stroke
				(width 0.1)
				(type default)
			)
			(layer "B.Fab")
		)
		(pad "1" smd rect
			(at 0.889 0 270)
			(size 1.016 1.27)
			(layers "B.Cu" "B.Mask" "B.Paste")
			(net "P1V8_CPU0_RT_1D")
		)
		(pad "2" smd rect
			(at -0.889 0 270)
			(size 1.016 1.27)
			(layers "B.Cu" "B.Mask" "B.Paste")
			(net "GND")
		)
	)
	(footprint ""
		(layer "B.Cu")
		(at 355.616002 -256.012188 -90)
		(property "Reference" "C2568"
			(at 0 0 90)
			(layer "B.SilkS")
			(hide yes)
			(effects
				(font
					(size 1.27 1.27)
				)
				(justify mirror)
			)
		)
		(property "Value" ""
			(at 0 0 90)
			(layer "B.Fab")
			(effects
				(font
					(size 1.27 1.27)
				)
				(justify mirror)
			)
		)
		(duplicate_pad_numbers_are_jumpers no)
		(fp_line
			(start -0.7874 0.4064)
			(end 0.7874 0.4064)
			(stroke
				(width 0.1524)
				(type default)
			)
			(layer "B.SilkS")
		)
		(fp_line
			(start 0.7874 0.4064)
			(end 0.7874 -0.4064)
			(stroke
				(width 0.1524)
				(type default)
			)
			(layer "B.SilkS")
		)
		(fp_line
			(start -0.7874 -0.4064)
			(end -0.7874 0.4064)
			(stroke
				(width 0.1524)
				(type default)
			)
			(layer "B.SilkS")
		)
		(fp_line
			(start 0.7874 -0.4064)
			(end -0.7874 -0.4064)
			(stroke
				(width 0.1524)
				(type default)
			)
			(layer "B.SilkS")
		)
		(fp_line
			(start -0.67945 0.3048)
			(end -0.120396 0.3048)
			(stroke
				(width 0.1)
				(type default)
			)
			(layer "B.Fab")
		)
		(fp_line
			(start -0.120396 0.3048)
			(end -0.120396 0.2794)
			(stroke
				(width 0.1)
				(type default)
			)
			(layer "B.Fab")
		)
		(fp_line
			(start 0.12065 0.3048)
			(end 0.67945 0.3048)
			(stroke
				(width 0.1)
				(type default)
			)
			(layer "B.Fab")
		)
		(fp_line
			(start 0.67945 0.3048)
			(end 0.67945 -0.305054)
			(stroke
				(width 0.1)
				(type default)
			)
			(layer "B.Fab")
		)
		(fp_line
			(start -0.120396 0.2794)
			(end 0.12065 0.2794)
			(stroke
				(width 0.1)
				(type default)
			)
			(layer "B.Fab")
		)
		(fp_line
			(start 0.12065 0.2794)
			(end 0.12065 0.3048)
			(stroke
				(width 0.1)
				(type default)
			)
			(layer "B.Fab")
		)
		(fp_line
			(start -0.12065 -0.2794)
			(end -0.12065 -0.3048)
			(stroke
				(width 0.1)
				(type default)
			)
			(layer "B.Fab")
		)
		(fp_line
			(start 0.12065 -0.2794)
			(end -0.12065 -0.2794)
			(stroke
				(width 0.1)
				(type default)
			)
			(layer "B.Fab")
		)
		(fp_line
			(start -0.67945 -0.3048)
			(end -0.67945 0.3048)
			(stroke
				(width 0.1)
				(type default)
			)
			(layer "B.Fab")
		)
		(fp_line
			(start -0.12065 -0.3048)
			(end -0.67945 -0.3048)
			(stroke
				(width 0.1)
				(type default)
			)
			(layer "B.Fab")
		)
		(fp_line
			(start 0.12065 -0.305054)
			(end 0.12065 -0.2794)
			(stroke
				(width 0.1)
				(type default)
			)
			(layer "B.Fab")
		)
		(fp_line
			(start 0.67945 -0.305054)
			(end 0.12065 -0.305054)
			(stroke
				(width 0.1)
				(type default)
			)
			(layer "B.Fab")
		)
		(pad "1" smd circle
			(at 0.40005 0 90)
			(size 0 0)
			(layers "B.Cu" "B.Mask" "B.Paste")
			(net "PVDDCR_SOC_P0")
		)
		(pad "2" smd circle
			(at -0.40005 0 90)
			(size 0 0)
			(layers "B.Cu" "B.Mask" "B.Paste")
			(net "GND")
		)
	)
	(footprint ""
		(layer "B.Cu")
		(at 69.753734 -185.396632 90)
		(property "Reference" "PC281_1"
			(at 0 0 90)
			(layer "B.SilkS")
			(hide yes)
			(effects
				(font
					(size 1.27 1.27)
				)
				(justify mirror)
			)
		)
		(property "Value" ""
			(at 0 0 90)
			(layer "B.Fab")
			(effects
				(font
					(size 1.27 1.27)
				)
				(justify mirror)
			)
		)
		(duplicate_pad_numbers_are_jumpers no)
		(fp_line
			(start 1.524 -0.762)
			(end -1.524 -0.762)
			(stroke
				(width 0.1524)
				(type default)
			)
			(layer "B.SilkS")
		)
		(fp_line
			(start -1.524 -0.762)
			(end -1.524 0.762)
			(stroke
				(width 0.1524)
				(type default)
			)
			(layer "B.SilkS")
		)
		(fp_line
			(start 1.524 0.762)
			(end 1.524 -0.762)
			(stroke
				(width 0.1524)
				(type default)
			)
			(layer "B.SilkS")
		)
		(fp_line
			(start -1.524 0.762)
			(end 1.524 0.762)
			(stroke
				(width 0.1524)
				(type default)
			)
			(layer "B.SilkS")
		)
		(fp_line
			(start 1.1049 -0.724916)
			(end 1.1049 0.724916)
			(stroke
				(width 0.1)
				(type default)
			)
			(layer "B.Fab")
		)
		(fp_line
			(start -1.1049 -0.724916)
			(end 1.1049 -0.724916)
			(stroke
				(width 0.1)
				(type default)
			)
			(layer "B.Fab")
		)
		(fp_line
			(start 1.1049 0.724916)
			(end -1.1049 0.724916)
			(stroke
				(width 0.1)
				(type default)
			)
			(layer "B.Fab")
		)
		(fp_line
			(start -1.1049 0.724916)
			(end -1.1049 -0.724916)
			(stroke
				(width 0.1)
				(type default)
			)
			(layer "B.Fab")
		)
		(pad "1" smd rect
			(at 0.889 0 90)
			(size 1.016 1.27)
			(layers "B.Cu" "B.Mask" "B.Paste")
			(net "PVDDCR_CPU0_P1")
		)
		(pad "2" smd rect
			(at -0.889 0 90)
			(size 1.016 1.27)
			(layers "B.Cu" "B.Mask" "B.Paste")
			(net "GND")
		)
	)
)
